(kicad_pcb
	(version 20260206)
	(generator "pcbnew")
	(generator_version "10.0")
	(general
		(thickness 1.6)
		(legacy_teardrops no)
	)
	(paper "A4")
	(title_block
		(title "12092022_DA0F0TMDCD0_F0T_Management_Board_D_brd_V3_OCP.brd")
		(comment 1 "Grand Teton / footprints 31-36 of 1440")
	)
	(layers
		(0 "F.Cu" signal "TOP")
		(4 "In1.Cu" signal "GND")
		(6 "In2.Cu" signal "IN1")
		(8 "In3.Cu" signal "GND1")
		(10 "In4.Cu" signal "IN2")
		(12 "In5.Cu" signal "VCC")
		(14 "In6.Cu" signal "VCC1")
		(16 "In7.Cu" signal "IN3")
		(18 "In8.Cu" signal "GND2")
		(20 "In9.Cu" signal "IN4")
		(22 "In10.Cu" signal "GND3")
		(2 "B.Cu" signal "BOTTOM")
		(9 "F.Adhes" user "F.Adhesive")
		(11 "B.Adhes" user "B.Adhesive")
		(13 "F.Paste" user "Package Geometry/Pastemask Top")
		(15 "B.Paste" user "Package Geometry/Pastemask Bottom")
		(5 "F.SilkS" user "Ref Des/Silkscreen Top")
		(7 "B.SilkS" user "Ref Des/Silkscreen Bottom")
		(1 "F.Mask" user "Board Geometry/Soldermask Top")
		(3 "B.Mask" user "Board Geometry/Soldermask Bottom")
		(17 "Dwgs.User" user "User.Drawings")
		(19 "Cmts.User" user "User.Comments")
		(21 "Eco1.User" user "User.Eco1")
		(23 "Eco2.User" user "User.Eco2")
		(25 "Edge.Cuts" user "Board Geometry/Outline")
		(27 "Margin" user)
		(31 "F.CrtYd" user "Package Geometry/Place Bound Top")
		(29 "B.CrtYd" user "Package Geometry/Place Bound Bottom")
		(35 "F.Fab" user "Ref Des/Assembly Top")
		(33 "B.Fab" user "Ref Des/Assembly Bottom")
	)
	(footprint ""
		(layer "F.Cu")
		(at 34.93135 -36.151058 90)
		(property "Reference" "R49"
			(at 0 0 90)
			(layer "F.SilkS")
			(hide yes)
			(effects
				(font
					(size 1.27 1.27)
				)
			)
		)
		(property "Value" ""
			(at 0 0 90)
			(layer "F.Fab")
			(effects
				(font
					(size 1.27 1.27)
				)
			)
		)
		(duplicate_pad_numbers_are_jumpers no)
		(fp_line
			(start 0.7874 -0.4064)
			(end 0.7874 0.4064)
			(stroke
				(width 0.1524)
				(type default)
			)
			(layer "F.SilkS")
		)
		(fp_line
			(start -0.7874 -0.4064)
			(end 0.7874 -0.4064)
			(stroke
				(width 0.1524)
				(type default)
			)
			(layer "F.SilkS")
		)
		(fp_line
			(start 0.7874 0.4064)
			(end -0.7874 0.4064)
			(stroke
				(width 0.1524)
				(type default)
			)
			(layer "F.SilkS")
		)
		(fp_line
			(start -0.7874 0.4064)
			(end -0.7874 -0.4064)
			(stroke
				(width 0.1524)
				(type default)
			)
			(layer "F.SilkS")
		)
		(fp_line
			(start -0.12065 -0.305054)
			(end -0.12065 -0.2794)
			(stroke
				(width 0.1)
				(type default)
			)
			(layer "F.Fab")
		)
		(fp_line
			(start -0.67945 -0.305054)
			(end -0.12065 -0.305054)
			(stroke
				(width 0.1)
				(type default)
			)
			(layer "F.Fab")
		)
		(fp_line
			(start 0.67945 -0.3048)
			(end 0.67945 0.3048)
			(stroke
				(width 0.1)
				(type default)
			)
			(layer "F.Fab")
		)
		(fp_line
			(start 0.12065 -0.3048)
			(end 0.67945 -0.3048)
			(stroke
				(width 0.1)
				(type default)
			)
			(layer "F.Fab")
		)
		(fp_line
			(start 0.12065 -0.2794)
			(end 0.12065 -0.3048)
			(stroke
				(width 0.1)
				(type default)
			)
			(layer "F.Fab")
		)
		(fp_line
			(start -0.12065 -0.2794)
			(end 0.12065 -0.2794)
			(stroke
				(width 0.1)
				(type default)
			)
			(layer "F.Fab")
		)
		(fp_line
			(start 0.120396 0.2794)
			(end -0.12065 0.2794)
			(stroke
				(width 0.1)
				(type default)
			)
			(layer "F.Fab")
		)
		(fp_line
			(start -0.12065 0.2794)
			(end -0.12065 0.3048)
			(stroke
				(width 0.1)
				(type default)
			)
			(layer "F.Fab")
		)
		(fp_line
			(start 0.67945 0.3048)
			(end 0.120396 0.3048)
			(stroke
				(width 0.1)
				(type default)
			)
			(layer "F.Fab")
		)
		(fp_line
			(start 0.120396 0.3048)
			(end 0.120396 0.2794)
			(stroke
				(width 0.1)
				(type default)
			)
			(layer "F.Fab")
		)
		(fp_line
			(start -0.12065 0.3048)
			(end -0.67945 0.3048)
			(stroke
				(width 0.1)
				(type default)
			)
			(layer "F.Fab")
		)
		(fp_line
			(start -0.67945 0.3048)
			(end -0.67945 -0.305054)
			(stroke
				(width 0.1)
				(type default)
			)
			(layer "F.Fab")
		)
		(pad "1" smd circle
			(at -0.40005 0 90)
			(size 0 0)
			(layers "F.Cu" "F.Mask" "F.Paste")
			(net "PWRGD_P1V0_AUX")
		)
		(pad "2" smd circle
			(at 0.40005 0 90)
			(size 0 0)
			(layers "F.Cu" "F.Mask" "F.Paste")
			(net "PWRGD_P1V0_AUX_R2")
		)
	)
	(footprint ""
		(layer "F.Cu")
		(at 70.600062 -3.3401)
		(property "Reference" "SW8"
			(at -5.516626 -6.306566 0)
			(unlocked yes)
			(layer "F.SilkS")
			(effects
				(font
					(size 0.7874 0.5842)
					(thickness 0.1524)
				)
				(justify left)
			)
		)
		(property "Value" ""
			(at 0 0 0)
			(layer "F.Fab")
			(effects
				(font
					(size 1.27 1.27)
				)
			)
		)
		(duplicate_pad_numbers_are_jumpers no)
		(fp_line
			(start -3.700018 -4.549902)
			(end -3.700018 -2.51206)
			(stroke
				(width 0.1524)
				(type default)
			)
			(layer "F.SilkS")
		)
		(fp_line
			(start -3.700018 -0.98806)
			(end -3.700018 -0.88646)
			(stroke
				(width 0.1524)
				(type default)
			)
			(layer "F.SilkS")
		)
		(fp_line
			(start -3.700018 1.39954)
			(end -3.700018 1.549908)
			(stroke
				(width 0.1524)
				(type default)
			)
			(layer "F.SilkS")
		)
		(fp_line
			(start -3.700018 1.549908)
			(end -1.75006 1.549908)
			(stroke
				(width 0.1524)
				(type default)
			)
			(layer "F.SilkS")
		)
		(fp_line
			(start -3.1496 -4.549902)
			(end -3.700018 -4.549902)
			(stroke
				(width 0.1524)
				(type default)
			)
			(layer "F.SilkS")
		)
		(fp_line
			(start -1.75006 1.549908)
			(end -1.75006 4.549902)
			(stroke
				(width 0.1524)
				(type default)
			)
			(layer "F.SilkS")
		)
		(fp_line
			(start -1.75006 4.549902)
			(end 1.75006 4.549902)
			(stroke
				(width 0.1524)
				(type default)
			)
			(layer "F.SilkS")
		)
		(fp_line
			(start 1.3716 -4.549902)
			(end -1.3716 -4.549902)
			(stroke
				(width 0.1524)
				(type default)
			)
			(layer "F.SilkS")
		)
		(fp_line
			(start 1.75006 1.549908)
			(end 3.700018 1.549908)
			(stroke
				(width 0.1524)
				(type default)
			)
			(layer "F.SilkS")
		)
		(fp_line
			(start 1.75006 4.549902)
			(end 1.75006 1.549908)
			(stroke
				(width 0.1524)
				(type default)
			)
			(layer "F.SilkS")
		)
		(fp_line
			(start 3.700018 -4.549902)
			(end 3.1496 -4.549902)
			(stroke
				(width 0.1524)
				(type default)
			)
			(layer "F.SilkS")
		)
		(fp_line
			(start 3.700018 -2.51206)
			(end 3.700018 -4.549902)
			(stroke
				(width 0.1524)
				(type default)
			)
			(layer "F.SilkS")
		)
		(fp_line
			(start 3.700018 -0.88646)
			(end 3.700018 -0.98806)
			(stroke
				(width 0.1524)
				(type default)
			)
			(layer "F.SilkS")
		)
		(fp_line
			(start 3.700018 1.549908)
			(end 3.700018 1.39954)
			(stroke
				(width 0.1524)
				(type default)
			)
			(layer "F.SilkS")
		)
		(fp_poly
			(pts
				(xy -2.249932 -5.286502) (xy -2.963418 -6.713474) (xy -1.536446 -6.713474)
			)
			(stroke
				(width 0)
				(type default)
			)
			(fill yes)
			(layer "F.SilkS")
		)
		(fp_line
			(start -3.700018 -4.549902)
			(end -3.700018 1.549908)
			(stroke
				(width 0.1)
				(type default)
			)
			(layer "F.Fab")
		)
		(fp_line
			(start -3.700018 1.549908)
			(end -1.75006 1.549908)
			(stroke
				(width 0.1)
				(type default)
			)
			(layer "F.Fab")
		)
		(fp_line
			(start -1.75006 1.549908)
			(end -1.75006 4.549902)
			(stroke
				(width 0.1)
				(type default)
			)
			(layer "F.Fab")
		)
		(fp_line
			(start -1.75006 4.549902)
			(end 1.75006 4.549902)
			(stroke
				(width 0.1)
				(type default)
			)
			(layer "F.Fab")
		)
		(fp_line
			(start 1.75006 1.549908)
			(end 3.700018 1.549908)
			(stroke
				(width 0.1)
				(type default)
			)
			(layer "F.Fab")
		)
		(fp_line
			(start 1.75006 4.549902)
			(end 1.75006 1.549908)
			(stroke
				(width 0.1)
				(type default)
			)
			(layer "F.Fab")
		)
		(fp_line
			(start 3.700018 -4.549902)
			(end -3.700018 -4.549902)
			(stroke
				(width 0.1)
				(type default)
			)
			(layer "F.Fab")
		)
		(fp_line
			(start 3.700018 1.549908)
			(end 3.700018 -4.549902)
			(stroke
				(width 0.1)
				(type default)
			)
			(layer "F.Fab")
		)
		(fp_poly
			(pts
				(xy -3.883914 -4.043934) (xy -5.310886 -3.330448) (xy -5.310886 -4.75742)
			)
			(stroke
				(width 0)
				(type default)
			)
			(fill yes)
			(layer "F.Fab")
		)
		(pad "" np_thru_hole circle
			(at -3.50012 -1.75006)
			(size 0.9144 0.9144)
			(drill 0.9144)
			(layers "*.Cu" "*.Mask")
			(clearance 0.381)
			(thermal_gap 0.381)
		)
		(pad "" np_thru_hole circle
			(at 3.50012 -1.75006)
			(size 0.9144 0.9144)
			(drill 0.9144)
			(layers "*.Cu" "*.Mask")
			(clearance 0.381)
			(thermal_gap 0.381)
		)
		(pad "1" smd rect
			(at -2.249932 -4.05003)
			(size 1.4986 2.0066)
			(layers "F.Cu" "F.Mask" "F.Paste")
			(net "GND")
		)
		(pad "2" smd rect
			(at 2.249932 -4.05003)
			(size 1.4986 2.0066)
			(layers "F.Cu" "F.Mask" "F.Paste")
			(net "REAR_AC_PWR_BTN")
		)
		(pad "3" smd rect
			(at -4.19989 0.249936)
			(size 2.0066 2.0066)
			(layers "F.Cu" "F.Mask" "F.Paste")
			(net "GND")
		)
		(pad "4" smd rect
			(at 4.19989 0.249936)
			(size 2.0066 2.0066)
			(layers "F.Cu" "F.Mask" "F.Paste")
			(net "GND")
		)
		(zone
			(layers "F.Cu" "B.Cu" "In1.Cu" "In2.Cu" "In3.Cu" "In4.Cu" "In5.Cu" "In6.Cu"
				"In7.Cu" "In8.Cu" "In9.Cu" "In10.Cu"
			)
			(hatch none 0.5)
			(connect_pads
				(clearance 0)
			)
			(min_thickness 0.25)
			(keepout
				(tracks not_allowed)
				(vias allowed)
				(pads allowed)
				(copperpour not_allowed)
				(footprints allowed)
			)
			(placement
				(enabled no)
				(sheetname "")
			)
			(fill
				(thermal_gap 0.5)
				(thermal_bridge_width 0.5)
				(island_removal_mode 0)
			)
			(polygon
				(pts
					(arc
						(start 67.963796 -5.09016)
						(mid 66.236088 -5.09016)
						(end 67.963796 -5.09016)
					)
				)
			)
		)
		(zone
			(layers "F.Cu" "B.Cu" "In1.Cu" "In2.Cu" "In3.Cu" "In4.Cu" "In5.Cu" "In6.Cu"
				"In7.Cu" "In8.Cu" "In9.Cu" "In10.Cu"
			)
			(hatch none 0.5)
			(connect_pads
				(clearance 0)
			)
			(min_thickness 0.25)
			(keepout
				(tracks not_allowed)
				(vias allowed)
				(pads allowed)
				(copperpour not_allowed)
				(footprints allowed)
			)
			(placement
				(enabled no)
				(sheetname "")
			)
			(fill
				(thermal_gap 0.5)
				(thermal_bridge_width 0.5)
				(island_removal_mode 0)
			)
			(polygon
				(pts
					(arc
						(start 74.963782 -5.09016)
						(mid 73.236582 -5.09016)
						(end 74.963782 -5.09016)
					)
				)
			)
		)
	)
	(footprint ""
		(layer "F.Cu")
		(at 10.287 -92.837 90)
		(property "Reference" "R285"
			(at 0 0 90)
			(layer "F.SilkS")
			(hide yes)
			(effects
				(font
					(size 1.27 1.27)
				)
			)
		)
		(property "Value" ""
			(at 0 0 90)
			(layer "F.Fab")
			(effects
				(font
					(size 1.27 1.27)
				)
			)
		)
		(duplicate_pad_numbers_are_jumpers no)
		(fp_line
			(start 0.7874 -0.4064)
			(end 0.7874 0.4064)
			(stroke
				(width 0.1524)
				(type default)
			)
			(layer "F.SilkS")
		)
		(fp_line
			(start -0.7874 -0.4064)
			(end 0.7874 -0.4064)
			(stroke
				(width 0.1524)
				(type default)
			)
			(layer "F.SilkS")
		)
		(fp_line
			(start 0.7874 0.4064)
			(end -0.7874 0.4064)
			(stroke
				(width 0.1524)
				(type default)
			)
			(layer "F.SilkS")
		)
		(fp_line
			(start -0.7874 0.4064)
			(end -0.7874 -0.4064)
			(stroke
				(width 0.1524)
				(type default)
			)
			(layer "F.SilkS")
		)
		(fp_line
			(start -0.12065 -0.305054)
			(end -0.12065 -0.2794)
			(stroke
				(width 0.1)
				(type default)
			)
			(layer "F.Fab")
		)
		(fp_line
			(start -0.67945 -0.305054)
			(end -0.12065 -0.305054)
			(stroke
				(width 0.1)
				(type default)
			)
			(layer "F.Fab")
		)
		(fp_line
			(start 0.67945 -0.3048)
			(end 0.67945 0.3048)
			(stroke
				(width 0.1)
				(type default)
			)
			(layer "F.Fab")
		)
		(fp_line
			(start 0.12065 -0.3048)
			(end 0.67945 -0.3048)
			(stroke
				(width 0.1)
				(type default)
			)
			(layer "F.Fab")
		)
		(fp_line
			(start 0.12065 -0.2794)
			(end 0.12065 -0.3048)
			(stroke
				(width 0.1)
				(type default)
			)
			(layer "F.Fab")
		)
		(fp_line
			(start -0.12065 -0.2794)
			(end 0.12065 -0.2794)
			(stroke
				(width 0.1)
				(type default)
			)
			(layer "F.Fab")
		)
		(fp_line
			(start 0.120396 0.2794)
			(end -0.12065 0.2794)
			(stroke
				(width 0.1)
				(type default)
			)
			(layer "F.Fab")
		)
		(fp_line
			(start -0.12065 0.2794)
			(end -0.12065 0.3048)
			(stroke
				(width 0.1)
				(type default)
			)
			(layer "F.Fab")
		)
		(fp_line
			(start 0.67945 0.3048)
			(end 0.120396 0.3048)
			(stroke
				(width 0.1)
				(type default)
			)
			(layer "F.Fab")
		)
		(fp_line
			(start 0.120396 0.3048)
			(end 0.120396 0.2794)
			(stroke
				(width 0.1)
				(type default)
			)
			(layer "F.Fab")
		)
		(fp_line
			(start -0.12065 0.3048)
			(end -0.67945 0.3048)
			(stroke
				(width 0.1)
				(type default)
			)
			(layer "F.Fab")
		)
		(fp_line
			(start -0.67945 0.3048)
			(end -0.67945 -0.305054)
			(stroke
				(width 0.1)
				(type default)
			)
			(layer "F.Fab")
		)
		(pad "1" smd circle
			(at -0.40005 0 90)
			(size 0 0)
			(layers "F.Cu" "F.Mask" "F.Paste")
			(net "JTAG_SCM_PLD_TCK")
		)
		(pad "2" smd circle
			(at 0.40005 0 90)
			(size 0 0)
			(layers "F.Cu" "F.Mask" "F.Paste")
			(net "GND")
		)
	)
	(footprint ""
		(layer "F.Cu")
		(at 61.5188 -30.861 90)
		(property "Reference" "R202"
			(at 0 0 90)
			(layer "F.SilkS")
			(hide yes)
			(effects
				(font
					(size 1.27 1.27)
				)
			)
		)
		(property "Value" ""
			(at 0 0 90)
			(layer "F.Fab")
			(effects
				(font
					(size 1.27 1.27)
				)
			)
		)
		(duplicate_pad_numbers_are_jumpers no)
		(fp_line
			(start 0.7874 -0.4064)
			(end 0.7874 0.4064)
			(stroke
				(width 0.1524)
				(type default)
			)
			(layer "F.SilkS")
		)
		(fp_line
			(start -0.7874 -0.4064)
			(end 0.7874 -0.4064)
			(stroke
				(width 0.1524)
				(type default)
			)
			(layer "F.SilkS")
		)
		(fp_line
			(start 0.7874 0.4064)
			(end -0.7874 0.4064)
			(stroke
				(width 0.1524)
				(type default)
			)
			(layer "F.SilkS")
		)
		(fp_line
			(start -0.7874 0.4064)
			(end -0.7874 -0.4064)
			(stroke
				(width 0.1524)
				(type default)
			)
			(layer "F.SilkS")
		)
		(fp_line
			(start -0.12065 -0.305054)
			(end -0.12065 -0.2794)
			(stroke
				(width 0.1)
				(type default)
			)
			(layer "F.Fab")
		)
		(fp_line
			(start -0.67945 -0.305054)
			(end -0.12065 -0.305054)
			(stroke
				(width 0.1)
				(type default)
			)
			(layer "F.Fab")
		)
		(fp_line
			(start 0.67945 -0.3048)
			(end 0.67945 0.3048)
			(stroke
				(width 0.1)
				(type default)
			)
			(layer "F.Fab")
		)
		(fp_line
			(start 0.12065 -0.3048)
			(end 0.67945 -0.3048)
			(stroke
				(width 0.1)
				(type default)
			)
			(layer "F.Fab")
		)
		(fp_line
			(start 0.12065 -0.2794)
			(end 0.12065 -0.3048)
			(stroke
				(width 0.1)
				(type default)
			)
			(layer "F.Fab")
		)
		(fp_line
			(start -0.12065 -0.2794)
			(end 0.12065 -0.2794)
			(stroke
				(width 0.1)
				(type default)
			)
			(layer "F.Fab")
		)
		(fp_line
			(start 0.120396 0.2794)
			(end -0.12065 0.2794)
			(stroke
				(width 0.1)
				(type default)
			)
			(layer "F.Fab")
		)
		(fp_line
			(start -0.12065 0.2794)
			(end -0.12065 0.3048)
			(stroke
				(width 0.1)
				(type default)
			)
			(layer "F.Fab")
		)
		(fp_line
			(start 0.67945 0.3048)
			(end 0.120396 0.3048)
			(stroke
				(width 0.1)
				(type default)
			)
			(layer "F.Fab")
		)
		(fp_line
			(start 0.120396 0.3048)
			(end 0.120396 0.2794)
			(stroke
				(width 0.1)
				(type default)
			)
			(layer "F.Fab")
		)
		(fp_line
			(start -0.12065 0.3048)
			(end -0.67945 0.3048)
			(stroke
				(width 0.1)
				(type default)
			)
			(layer "F.Fab")
		)
		(fp_line
			(start -0.67945 0.3048)
			(end -0.67945 -0.305054)
			(stroke
				(width 0.1)
				(type default)
			)
			(layer "F.Fab")
		)
		(pad "1" smd circle
			(at -0.40005 0 90)
			(size 0 0)
			(layers "F.Cu" "F.Mask" "F.Paste")
			(net "GND")
		)
		(pad "2" smd circle
			(at 0.40005 0 90)
			(size 0 0)
			(layers "F.Cu" "F.Mask" "F.Paste")
			(net "JTAG_SCM_TCK")
		)
	)
	(footprint ""
		(layer "F.Cu")
		(at 51.562 -20.32)
		(property "Reference" "C177"
			(at 0 0 0)
			(layer "F.SilkS")
			(hide yes)
			(effects
				(font
					(size 1.27 1.27)
				)
			)
		)
		(property "Value" ""
			(at 0 0 0)
			(layer "F.Fab")
			(effects
				(font
					(size 1.27 1.27)
				)
			)
		)
		(duplicate_pad_numbers_are_jumpers no)
		(fp_line
			(start -2.2098 -0.9398)
			(end 2.2098 -0.9398)
			(stroke
				(width 0.1524)
				(type default)
			)
			(layer "F.SilkS")
		)
		(fp_line
			(start -2.2098 0.9398)
			(end -2.2098 -0.9398)
			(stroke
				(width 0.1524)
				(type default)
			)
			(layer "F.SilkS")
		)
		(fp_line
			(start 2.2098 -0.9398)
			(end 2.2098 0.9398)
			(stroke
				(width 0.1524)
				(type default)
			)
			(layer "F.SilkS")
		)
		(fp_line
			(start 2.2098 0.9398)
			(end -2.2098 0.9398)
			(stroke
				(width 0.1524)
				(type default)
			)
			(layer "F.SilkS")
		)
		(fp_line
			(start -1.700022 -0.899922)
			(end 1.700022 -0.899922)
			(stroke
				(width 0.1)
				(type default)
			)
			(layer "F.Fab")
		)
		(fp_line
			(start -1.700022 0.899922)
			(end -1.700022 -0.899922)
			(stroke
				(width 0.1)
				(type default)
			)
			(layer "F.Fab")
		)
		(fp_line
			(start 1.700022 -0.899922)
			(end 1.700022 0.899922)
			(stroke
				(width 0.1)
				(type default)
			)
			(layer "F.Fab")
		)
		(fp_line
			(start 1.700022 0.899922)
			(end -1.700022 0.899922)
			(stroke
				(width 0.1)
				(type default)
			)
			(layer "F.Fab")
		)
		(pad "1" smd rect
			(at -1.4732 0 180)
			(size 1.1684 1.5748)
			(layers "F.Cu" "F.Mask" "F.Paste")
			(net "P5V_USB_REAR")
		)
		(pad "2" smd rect
			(at 1.4732 0 180)
			(size 1.1684 1.5748)
			(layers "F.Cu" "F.Mask" "F.Paste")
			(net "GND")
		)
	)
	(footprint ""
		(layer "F.Cu")
		(at 76.499974 -107.700064)
		(property "Reference" "H3"
			(at 1.279652 -3.484118 0)
			(unlocked yes)
			(layer "F.SilkS")
			(effects
				(font
					(size 0.7874 0.5842)
					(thickness 0.1524)
				)
				(justify left)
			)
		)
		(property "Value" ""
			(at 0 0 0)
			(layer "F.Fab")
			(effects
				(font
					(size 1.27 1.27)
				)
			)
		)
		(duplicate_pad_numbers_are_jumpers no)
		(pad "1" thru_hole circle
			(at 0 0)
			(size 6.0198 6.0198)
			(drill 3.4036)
			(layers "*.Cu" "*.Mask")
			(remove_unused_layers no)
			(net "GND")
			(clearance -1.0541)
		)
	)
)
